(kicad_pcb
	(version 20260206)
	(generator "pcbnew")
	(generator_version "10.0")
	(general
		(thickness 1.6)
		(legacy_teardrops no)
	)
	(paper "A4")
	(title_block
		(title "fcb — 12433-1M.1206WZS1330.brd")
		(comment 1 "Open Vault / Knox (Wiwynn) / footprints 392-398 of 495")
	)
	(layers
		(0 "F.Cu" signal "TOP")
		(4 "In1.Cu" signal "L2GND")
		(6 "In2.Cu" signal "L3VCC")
		(2 "B.Cu" signal "BOTTOM")
		(9 "F.Adhes" user "F.Adhesive")
		(11 "B.Adhes" user "B.Adhesive")
		(13 "F.Paste" user "Package Geometry/Pastemask Top")
		(15 "B.Paste" user "Package Geometry/Pastemask Bottom")
		(5 "F.SilkS" user "Ref Des/Silkscreen Top")
		(7 "B.SilkS" user "Ref Des/Silkscreen Bottom")
		(1 "F.Mask" user "Board Geometry/Soldermask Top")
		(3 "B.Mask" user "Board Geometry/Soldermask Bottom")
		(17 "Dwgs.User" user "User.Drawings")
		(19 "Cmts.User" user "User.Comments")
		(21 "Eco1.User" user "User.Eco1")
		(23 "Eco2.User" user "User.Eco2")
		(25 "Edge.Cuts" user "Board Geometry/Outline")
		(27 "Margin" user)
		(31 "F.CrtYd" user "Package Geometry/Place Bound Top")
		(29 "B.CrtYd" user "Package Geometry/Place Bound Bottom")
		(35 "F.Fab" user "Ref Des/Assembly Top")
		(33 "B.Fab" user "Ref Des/Assembly Bottom")
	)
	(footprint ""
		(layer "F.Cu")
		(at 36.195 -176.657 -90)
		(property "Reference" "C256"
			(at 0 0 270)
			(layer "F.SilkS")
			(hide yes)
			(effects
				(font
					(size 1.27 1.27)
				)
			)
		)
		(property "Value" "SCD1U16V2KX-3GP"
			(at 1.1811 -2.7051 270)
			(unlocked yes)
			(layer "F.Fab")
			(hide yes)
			(effects
				(font
					(size 1.016 1.016)
					(thickness 0.1524)
				)
			)
		)
		(property "Device Type" "C402H22"
			(at 1.1811 -4.2291 270)
			(unlocked yes)
			(layer "F.Fab")
			(hide yes)
			(effects
				(font
					(size 1.016 1.016)
					(thickness 0.1524)
				)
			)
		)
		(duplicate_pad_numbers_are_jumpers no)
		(fp_rect
			(start -0.4318 0.9525)
			(end 0.4318 -0.9525)
			(stroke
				(width 0)
				(type default)
			)
			(fill no)
			(layer "F.CrtYd")
		)
		(fp_rect
			(start -0.4318 0.9525)
			(end 0.4318 -0.9525)
			(stroke
				(width 0)
				(type default)
			)
			(fill no)
			(layer "F.Fab")
		)
		(pad "1" smd custom
			(at 0 -0.4445 270)
			(size 0.1524 0.1524)
			(layers "F.Cu" "F.Mask" "F.Paste")
			(net "TEMP_ALM#_IN_D")
			(options
				(clearance outline)
				(anchor circle)
			)
			(primitives
				(gr_poly
					(pts
						(arc
							(start 0.3048 -0.2032)
							(mid 0.275042 -0.275042)
							(end 0.2032 -0.3048)
						)
						(arc
							(start -0.2032 -0.3048)
							(mid -0.275042 -0.275042)
							(end -0.3048 -0.2032)
						)
						(arc
							(start -0.3048 0.2032)
							(mid -0.275042 0.275042)
							(end -0.2032 0.3048)
						)
						(arc
							(start 0.2032 0.3048)
							(mid 0.275042 0.275042)
							(end 0.3048 0.2032)
						)
					)
					(width 0)
					(fill yes)
				)
			)
		)
		(pad "2" smd custom
			(at 0 0.4445 270)
			(size 0.1524 0.1524)
			(layers "F.Cu" "F.Mask" "F.Paste")
			(net "GND")
			(options
				(clearance outline)
				(anchor circle)
			)
			(primitives
				(gr_poly
					(pts
						(arc
							(start 0.3048 -0.2032)
							(mid 0.275042 -0.275042)
							(end 0.2032 -0.3048)
						)
						(arc
							(start -0.2032 -0.3048)
							(mid -0.275042 -0.275042)
							(end -0.3048 -0.2032)
						)
						(arc
							(start -0.3048 0.2032)
							(mid -0.275042 0.275042)
							(end -0.2032 0.3048)
						)
						(arc
							(start 0.2032 0.3048)
							(mid 0.275042 0.275042)
							(end 0.3048 0.2032)
						)
					)
					(width 0)
					(fill yes)
				)
			)
		)
	)
	(footprint ""
		(layer "F.Cu")
		(at 4.040124 -372.65991 -90)
		(property "Reference" "CN2"
			(at 0 0 270)
			(layer "F.SilkS")
			(hide yes)
			(effects
				(font
					(size 1.27 1.27)
				)
			)
		)
		(property "Value" "JWT-CON5-42-GP"
			(at -7.8105 2.9591 270)
			(unlocked yes)
			(layer "F.Fab")
			(hide yes)
			(effects
				(font
					(size 1.016 1.016)
					(thickness 0.1524)
				)
			)
		)
		(property "Device Type" "A2541WR0-1TX5PA-6T-0E"
			(at -7.8105 1.4351 270)
			(unlocked yes)
			(layer "F.Fab")
			(hide yes)
			(effects
				(font
					(size 1.016 1.016)
					(thickness 0.1524)
				)
			)
		)
		(duplicate_pad_numbers_are_jumpers no)
		(fp_line
			(start -6.604 10.287)
			(end 6.604 10.287)
			(stroke
				(width 0.1524)
				(type default)
			)
			(layer "F.SilkS")
		)
		(fp_line
			(start 6.604 10.287)
			(end 6.604 -0.9652)
			(stroke
				(width 0.1524)
				(type default)
			)
			(layer "F.SilkS")
		)
		(fp_line
			(start -6.604 -0.9652)
			(end -6.604 10.287)
			(stroke
				(width 0.1524)
				(type default)
			)
			(layer "F.SilkS")
		)
		(fp_line
			(start 6.604 -0.9652)
			(end -6.604 -0.9652)
			(stroke
				(width 0.1524)
				(type default)
			)
			(layer "F.SilkS")
		)
		(fp_line
			(start -6.731 -1.0922)
			(end -6.731 0.1778)
			(stroke
				(width 0.4064)
				(type default)
			)
			(layer "F.SilkS")
		)
		(fp_line
			(start -5.461 -1.0922)
			(end -6.731 -1.0922)
			(stroke
				(width 0.4064)
				(type default)
			)
			(layer "F.SilkS")
		)
		(fp_circle
			(center -5.08 0)
			(end -5.08 -1.0668)
			(stroke
				(width 0.3048)
				(type default)
			)
			(fill no)
			(layer "F.SilkS")
		)
		(fp_circle
			(center -2.54 0)
			(end -2.54 -1.0668)
			(stroke
				(width 0.3048)
				(type default)
			)
			(fill no)
			(layer "F.SilkS")
		)
		(fp_circle
			(center 0 0)
			(end 0 -1.0668)
			(stroke
				(width 0.3048)
				(type default)
			)
			(fill no)
			(layer "F.SilkS")
		)
		(fp_circle
			(center 2.54 0)
			(end 2.54 -1.0668)
			(stroke
				(width 0.3048)
				(type default)
			)
			(fill no)
			(layer "F.SilkS")
		)
		(fp_circle
			(center 5.08 0)
			(end 5.08 -1.0668)
			(stroke
				(width 0.3048)
				(type default)
			)
			(fill no)
			(layer "F.SilkS")
		)
		(fp_rect
			(start -6.35 10.033)
			(end 6.35 -0.3302)
			(stroke
				(width 0)
				(type default)
			)
			(fill no)
			(layer "F.CrtYd")
		)
		(fp_poly
			(pts
				(xy -6.35 -0.3302) (xy 6.858 -0.3302) (xy 6.858 -1.2192) (xy -6.858 -1.2192) (xy -6.858 10.541)
				(xy 6.858 10.541) (xy 6.858 -0.3175) (xy 6.35 -0.3175) (xy 6.35 10.033) (xy -6.35 10.033)
			)
			(stroke
				(width 0)
				(type default)
			)
			(fill no)
			(layer "F.CrtYd")
		)
		(fp_rect
			(start -6.858 10.541)
			(end 6.858 -1.2192)
			(stroke
				(width 0)
				(type default)
			)
			(fill no)
			(layer "F.Fab")
		)
		(pad "1" thru_hole circle
			(at -5.08 0 270)
			(size 1.4224 1.4224)
			(drill 1.016)
			(layers "*.Cu" "*.Mask")
			(remove_unused_layers no)
			(net "GND")
			(clearance 0.1524)
			(thermal_gap 0.1524)
		)
		(pad "2" thru_hole circle
			(at -2.54 0 270)
			(size 1.4224 1.4224)
			(drill 1.016)
			(layers "*.Cu" "*.Mask")
			(remove_unused_layers no)
			(net "P12V_FAN2")
			(clearance 0.1524)
			(thermal_gap 0.1524)
		)
		(pad "3" thru_hole circle
			(at 0 0 270)
			(size 1.4224 1.4224)
			(drill 1.016)
			(layers "*.Cu" "*.Mask")
			(remove_unused_layers no)
			(net "FAN_TACH4")
			(clearance 0.1524)
			(thermal_gap 0.1524)
		)
		(pad "4" thru_hole circle
			(at 2.54 0 270)
			(size 1.4224 1.4224)
			(drill 1.016)
			(layers "*.Cu" "*.Mask")
			(remove_unused_layers no)
			(net "PWM_OUT_FAN2_NET")
			(clearance 0.1524)
			(thermal_gap 0.1524)
		)
		(pad "5" thru_hole circle
			(at 5.08 0 270)
			(size 1.4224 1.4224)
			(drill 1.016)
			(layers "*.Cu" "*.Mask")
			(remove_unused_layers no)
			(net "FAN_TACH3")
			(clearance 0.1524)
			(thermal_gap 0.1524)
		)
	)
	(footprint ""
		(layer "F.Cu")
		(at 4.897882 -78.481428)
		(property "Reference" "R113"
			(at 0 0 0)
			(layer "F.SilkS")
			(hide yes)
			(effects
				(font
					(size 1.27 1.27)
				)
			)
		)
		(property "Value" "2KR2F-3-GP"
			(at 0.064008 -3.993896 0)
			(unlocked yes)
			(layer "F.Fab")
			(hide yes)
			(effects
				(font
					(size 1.016 1.016)
					(thickness 0.1524)
				)
			)
		)
		(property "Device Type" "R402H16"
			(at 0.064008 -5.517896 0)
			(unlocked yes)
			(layer "F.Fab")
			(hide yes)
			(effects
				(font
					(size 1.016 1.016)
					(thickness 0.1524)
				)
			)
		)
		(duplicate_pad_numbers_are_jumpers no)
		(fp_line
			(start -0.508 -0.9398)
			(end -0.508 0.9398)
			(stroke
				(width 0.1524)
				(type default)
			)
			(layer "F.SilkS")
		)
		(fp_line
			(start 0.508 -0.9398)
			(end -0.508 -0.9398)
			(stroke
				(width 0.1524)
				(type default)
			)
			(layer "F.SilkS")
		)
		(fp_rect
			(start -0.508 0.9398)
			(end 0.508 -0.9398)
			(stroke
				(width 0)
				(type default)
			)
			(fill no)
			(layer "F.CrtYd")
		)
		(fp_rect
			(start -0.508 0.9398)
			(end 0.508 -0.9398)
			(stroke
				(width 0)
				(type default)
			)
			(fill no)
			(layer "F.Fab")
		)
		(pad "1" smd custom
			(at 0 -0.4445)
			(size 0.1397 0.1397)
			(layers "F.Cu" "F.Mask" "F.Paste")
			(net "LED_DR_LED4")
			(options
				(clearance outline)
				(anchor circle)
			)
			(primitives
				(gr_poly
					(pts
						(arc
							(start -0.1778 -0.2794)
							(mid -0.249642 -0.249642)
							(end -0.2794 -0.1778)
						)
						(arc
							(start -0.2794 0.1778)
							(mid -0.249642 0.249642)
							(end -0.1778 0.2794)
						)
						(arc
							(start 0.1778 0.2794)
							(mid 0.249642 0.249642)
							(end 0.2794 0.1778)
						)
						(arc
							(start 0.2794 -0.1778)
							(mid 0.249642 -0.249642)
							(end 0.1778 -0.2794)
						)
					)
					(width 0)
					(fill yes)
				)
			)
		)
		(pad "2" smd custom
			(at 0 0.4445)
			(size 0.1397 0.1397)
			(layers "F.Cu" "F.Mask" "F.Paste")
			(net "LED_DR_LED4_B")
			(options
				(clearance outline)
				(anchor circle)
			)
			(primitives
				(gr_poly
					(pts
						(arc
							(start -0.1778 -0.2794)
							(mid -0.249642 -0.249642)
							(end -0.2794 -0.1778)
						)
						(arc
							(start -0.2794 0.1778)
							(mid -0.249642 0.249642)
							(end -0.1778 0.2794)
						)
						(arc
							(start 0.1778 0.2794)
							(mid 0.249642 0.249642)
							(end 0.2794 0.1778)
						)
						(arc
							(start 0.2794 -0.1778)
							(mid 0.249642 -0.249642)
							(end 0.1778 -0.2794)
						)
					)
					(width 0)
					(fill yes)
				)
			)
		)
	)
	(footprint ""
		(layer "F.Cu")
		(at 41.0464 -138.5824 90)
		(property "Reference" "PR101"
			(at 0 0 90)
			(layer "F.SilkS")
			(hide yes)
			(effects
				(font
					(size 1.27 1.27)
				)
			)
		)
		(property "Value" "100R2F-L1-GP-U"
			(at 0.064008 -3.993896 90)
			(unlocked yes)
			(layer "F.Fab")
			(hide yes)
			(effects
				(font
					(size 1.016 1.016)
					(thickness 0.1524)
				)
			)
		)
		(property "Device Type" "R402H14"
			(at 0.064008 -5.517896 90)
			(unlocked yes)
			(layer "F.Fab")
			(hide yes)
			(effects
				(font
					(size 1.016 1.016)
					(thickness 0.1524)
				)
			)
		)
		(duplicate_pad_numbers_are_jumpers no)
		(fp_line
			(start 0.508 -0.9398)
			(end -0.508 -0.9398)
			(stroke
				(width 0.1524)
				(type default)
			)
			(layer "F.SilkS")
		)
		(fp_line
			(start -0.508 -0.9398)
			(end -0.508 0.9398)
			(stroke
				(width 0.1524)
				(type default)
			)
			(layer "F.SilkS")
		)
		(fp_rect
			(start -0.508 0.9398)
			(end 0.508 -0.9398)
			(stroke
				(width 0)
				(type default)
			)
			(fill no)
			(layer "F.CrtYd")
		)
		(fp_rect
			(start -0.508 0.9398)
			(end 0.508 -0.9398)
			(stroke
				(width 0)
				(type default)
			)
			(fill no)
			(layer "F.Fab")
		)
		(pad "1" smd custom
			(at 0 -0.4445 90)
			(size 0.1397 0.1397)
			(layers "F.Cu" "F.Mask" "F.Paste")
			(net "P12VL_2490_GATE")
			(options
				(clearance outline)
				(anchor circle)
			)
			(primitives
				(gr_poly
					(pts
						(arc
							(start -0.1778 -0.2794)
							(mid -0.249642 -0.249642)
							(end -0.2794 -0.1778)
						)
						(arc
							(start -0.2794 0.1778)
							(mid -0.249642 0.249642)
							(end -0.1778 0.2794)
						)
						(arc
							(start 0.1778 0.2794)
							(mid 0.249642 0.249642)
							(end 0.2794 0.1778)
						)
						(arc
							(start 0.2794 -0.1778)
							(mid 0.249642 -0.249642)
							(end 0.1778 -0.2794)
						)
					)
					(width 0)
					(fill yes)
				)
			)
		)
		(pad "2" smd custom
			(at 0 0.4445 90)
			(size 0.1397 0.1397)
			(layers "F.Cu" "F.Mask" "F.Paste")
			(net "P12VL_2490_RC")
			(options
				(clearance outline)
				(anchor circle)
			)
			(primitives
				(gr_poly
					(pts
						(arc
							(start -0.1778 -0.2794)
							(mid -0.249642 -0.249642)
							(end -0.2794 -0.1778)
						)
						(arc
							(start -0.2794 0.1778)
							(mid -0.249642 0.249642)
							(end -0.1778 0.2794)
						)
						(arc
							(start 0.1778 0.2794)
							(mid 0.249642 0.249642)
							(end 0.2794 0.1778)
						)
						(arc
							(start 0.2794 -0.1778)
							(mid 0.249642 -0.249642)
							(end 0.1778 -0.2794)
						)
					)
					(width 0)
					(fill yes)
				)
			)
		)
	)
	(footprint ""
		(layer "F.Cu")
		(at 39.064184 -359.41 90)
		(property "Reference" "PR58"
			(at 0 0 90)
			(layer "F.SilkS")
			(hide yes)
			(effects
				(font
					(size 1.27 1.27)
				)
			)
		)
		(property "Value" "10KR2F-2-GP"
			(at 0.064008 -3.993896 90)
			(unlocked yes)
			(layer "F.Fab")
			(hide yes)
			(effects
				(font
					(size 1.016 1.016)
					(thickness 0.1524)
				)
			)
		)
		(property "Device Type" "R402H16"
			(at 0.064008 -5.517896 90)
			(unlocked yes)
			(layer "F.Fab")
			(hide yes)
			(effects
				(font
					(size 1.016 1.016)
					(thickness 0.1524)
				)
			)
		)
		(duplicate_pad_numbers_are_jumpers no)
		(fp_line
			(start 0.508 -0.9398)
			(end -0.508 -0.9398)
			(stroke
				(width 0.1524)
				(type default)
			)
			(layer "F.SilkS")
		)
		(fp_line
			(start -0.508 -0.9398)
			(end -0.508 0.9398)
			(stroke
				(width 0.1524)
				(type default)
			)
			(layer "F.SilkS")
		)
		(fp_rect
			(start -0.508 0.9398)
			(end 0.508 -0.9398)
			(stroke
				(width 0)
				(type default)
			)
			(fill no)
			(layer "F.CrtYd")
		)
		(fp_rect
			(start -0.508 0.9398)
			(end 0.508 -0.9398)
			(stroke
				(width 0)
				(type default)
			)
			(fill no)
			(layer "F.Fab")
		)
		(pad "1" smd custom
			(at 0 -0.4445 90)
			(size 0.1397 0.1397)
			(layers "F.Cu" "F.Mask" "F.Paste")
			(net "P12V_AUX")
			(options
				(clearance outline)
				(anchor circle)
			)
			(primitives
				(gr_poly
					(pts
						(arc
							(start -0.1778 -0.2794)
							(mid -0.249642 -0.249642)
							(end -0.2794 -0.1778)
						)
						(arc
							(start -0.2794 0.1778)
							(mid -0.249642 0.249642)
							(end -0.1778 0.2794)
						)
						(arc
							(start 0.1778 0.2794)
							(mid 0.249642 0.249642)
							(end 0.2794 0.1778)
						)
						(arc
							(start 0.2794 -0.1778)
							(mid 0.249642 -0.249642)
							(end 0.1778 -0.2794)
						)
					)
					(width 0)
					(fill yes)
				)
			)
		)
		(pad "2" smd custom
			(at 0 0.4445 90)
			(size 0.1397 0.1397)
			(layers "F.Cu" "F.Mask" "F.Paste")
			(net "OTP_RETRY_C")
			(options
				(clearance outline)
				(anchor circle)
			)
			(primitives
				(gr_poly
					(pts
						(arc
							(start -0.1778 -0.2794)
							(mid -0.249642 -0.249642)
							(end -0.2794 -0.1778)
						)
						(arc
							(start -0.2794 0.1778)
							(mid -0.249642 0.249642)
							(end -0.1778 0.2794)
						)
						(arc
							(start 0.1778 0.2794)
							(mid 0.249642 0.249642)
							(end 0.2794 0.1778)
						)
						(arc
							(start 0.2794 -0.1778)
							(mid 0.249642 -0.249642)
							(end 0.1778 -0.2794)
						)
					)
					(width 0)
					(fill yes)
				)
			)
		)
	)
	(footprint ""
		(layer "F.Cu")
		(at 33.401 -363.728 -90)
		(property "Reference" "C51"
			(at 0 0 270)
			(layer "F.SilkS")
			(hide yes)
			(effects
				(font
					(size 1.27 1.27)
				)
			)
		)
		(property "Value" "SCD1U10V2KX-4-LL-GP"
			(at 1.1811 -2.7051 270)
			(unlocked yes)
			(layer "F.Fab")
			(hide yes)
			(effects
				(font
					(size 1.016 1.016)
					(thickness 0.1524)
				)
			)
		)
		(property "Device Type" "C402H22"
			(at 1.1811 -4.2291 270)
			(unlocked yes)
			(layer "F.Fab")
			(hide yes)
			(effects
				(font
					(size 1.016 1.016)
					(thickness 0.1524)
				)
			)
		)
		(duplicate_pad_numbers_are_jumpers no)
		(fp_rect
			(start -0.4318 0.9525)
			(end 0.4318 -0.9525)
			(stroke
				(width 0)
				(type default)
			)
			(fill no)
			(layer "F.CrtYd")
		)
		(fp_rect
			(start -0.4318 0.9525)
			(end 0.4318 -0.9525)
			(stroke
				(width 0)
				(type default)
			)
			(fill no)
			(layer "F.Fab")
		)
		(pad "1" smd custom
			(at 0 -0.4445 270)
			(size 0.1524 0.1524)
			(layers "F.Cu" "F.Mask" "F.Paste")
			(net "TEMP_ALM#_REVERSE_R")
			(options
				(clearance outline)
				(anchor circle)
			)
			(primitives
				(gr_poly
					(pts
						(arc
							(start 0.3048 -0.2032)
							(mid 0.275042 -0.275042)
							(end 0.2032 -0.3048)
						)
						(arc
							(start -0.2032 -0.3048)
							(mid -0.275042 -0.275042)
							(end -0.3048 -0.2032)
						)
						(arc
							(start -0.3048 0.2032)
							(mid -0.275042 0.275042)
							(end -0.2032 0.3048)
						)
						(arc
							(start 0.2032 0.3048)
							(mid 0.275042 0.275042)
							(end 0.3048 0.2032)
						)
					)
					(width 0)
					(fill yes)
				)
			)
		)
		(pad "2" smd custom
			(at 0 0.4445 270)
			(size 0.1524 0.1524)
			(layers "F.Cu" "F.Mask" "F.Paste")
			(net "GND")
			(options
				(clearance outline)
				(anchor circle)
			)
			(primitives
				(gr_poly
					(pts
						(arc
							(start 0.3048 -0.2032)
							(mid 0.275042 -0.275042)
							(end 0.2032 -0.3048)
						)
						(arc
							(start -0.2032 -0.3048)
							(mid -0.275042 -0.275042)
							(end -0.3048 -0.2032)
						)
						(arc
							(start -0.3048 0.2032)
							(mid -0.275042 0.275042)
							(end -0.2032 0.3048)
						)
						(arc
							(start 0.2032 0.3048)
							(mid 0.275042 0.275042)
							(end 0.3048 0.2032)
						)
					)
					(width 0)
					(fill yes)
				)
			)
		)
	)
	(footprint ""
		(layer "F.Cu")
		(at 21.844 -376.936 90)
		(property "Reference" "PR34"
			(at 0 0 90)
			(layer "F.SilkS")
			(hide yes)
			(effects
				(font
					(size 1.27 1.27)
				)
			)
		)
		(property "Value" "51KR2F-L-GP"
			(at 0.064008 -3.993896 90)
			(unlocked yes)
			(layer "F.Fab")
			(hide yes)
			(effects
				(font
					(size 1.016 1.016)
					(thickness 0.1524)
				)
			)
		)
		(property "Device Type" "R402H16"
			(at 0.064008 -5.517896 90)
			(unlocked yes)
			(layer "F.Fab")
			(hide yes)
			(effects
				(font
					(size 1.016 1.016)
					(thickness 0.1524)
				)
			)
		)
		(duplicate_pad_numbers_are_jumpers no)
		(fp_line
			(start 0.508 -0.9398)
			(end -0.508 -0.9398)
			(stroke
				(width 0.1524)
				(type default)
			)
			(layer "F.SilkS")
		)
		(fp_line
			(start -0.508 -0.9398)
			(end -0.508 0.9398)
			(stroke
				(width 0.1524)
				(type default)
			)
			(layer "F.SilkS")
		)
		(fp_rect
			(start -0.508 0.9398)
			(end 0.508 -0.9398)
			(stroke
				(width 0)
				(type default)
			)
			(fill no)
			(layer "F.CrtYd")
		)
		(fp_rect
			(start -0.508 0.9398)
			(end 0.508 -0.9398)
			(stroke
				(width 0)
				(type default)
			)
			(fill no)
			(layer "F.Fab")
		)
		(pad "1" smd custom
			(at 0 -0.4445 90)
			(size 0.1397 0.1397)
			(layers "F.Cu" "F.Mask" "F.Paste")
			(net "P12V_AUX")
			(options
				(clearance outline)
				(anchor circle)
			)
			(primitives
				(gr_poly
					(pts
						(arc
							(start -0.1778 -0.2794)
							(mid -0.249642 -0.249642)
							(end -0.2794 -0.1778)
						)
						(arc
							(start -0.2794 0.1778)
							(mid -0.249642 0.249642)
							(end -0.1778 0.2794)
						)
						(arc
							(start 0.1778 0.2794)
							(mid 0.249642 0.249642)
							(end 0.2794 0.1778)
						)
						(arc
							(start 0.2794 -0.1778)
							(mid 0.249642 -0.249642)
							(end 0.1778 -0.2794)
						)
					)
					(width 0)
					(fill yes)
				)
			)
		)
		(pad "2" smd custom
			(at 0 0.4445 90)
			(size 0.1397 0.1397)
			(layers "F.Cu" "F.Mask" "F.Paste")
			(net "ADM1276_UV")
			(options
				(clearance outline)
				(anchor circle)
			)
			(primitives
				(gr_poly
					(pts
						(arc
							(start -0.1778 -0.2794)
							(mid -0.249642 -0.249642)
							(end -0.2794 -0.1778)
						)
						(arc
							(start -0.2794 0.1778)
							(mid -0.249642 0.249642)
							(end -0.1778 0.2794)
						)
						(arc
							(start 0.1778 0.2794)
							(mid 0.249642 0.249642)
							(end 0.2794 0.1778)
						)
						(arc
							(start 0.2794 -0.1778)
							(mid 0.249642 -0.249642)
							(end 0.1778 -0.2794)
						)
					)
					(width 0)
					(fill yes)
				)
			)
		)
	)
)
